(kicad_pcb
	(version 20260206)
	(generator "pcbnew")
	(generator_version "10.0")
	(general
		(thickness 1.6)
		(legacy_teardrops no)
	)
	(paper "A4")
	(title_block
		(title "04192023_DAF0TMB3IC0_F0TG_MB_C_brd_V02_OCP.brd")
		(comment 1 "Grand Teton / footprints 470-476 of 8354")
	)
	(layers
		(0 "F.Cu" signal "TOP")
		(4 "In1.Cu" signal "GND")
		(6 "In2.Cu" signal "IN1")
		(8 "In3.Cu" signal "GND1")
		(10 "In4.Cu" signal "IN2")
		(12 "In5.Cu" signal "GND2")
		(14 "In6.Cu" signal "IN3")
		(16 "In7.Cu" signal "GND3")
		(18 "In8.Cu" signal "VCC")
		(20 "In9.Cu" signal "VCC1")
		(22 "In10.Cu" signal "GND4")
		(24 "In11.Cu" signal "IN4")
		(26 "In12.Cu" signal "GND5")
		(28 "In13.Cu" signal "IN5")
		(30 "In14.Cu" signal "GND6")
		(32 "In15.Cu" signal "IN6")
		(34 "In16.Cu" signal "GND7")
		(2 "B.Cu" signal "BOTTOM")
		(9 "F.Adhes" user "F.Adhesive")
		(11 "B.Adhes" user "B.Adhesive")
		(13 "F.Paste" user "Package Geometry/Pastemask Top")
		(15 "B.Paste" user "Package Geometry/Pastemask Bottom")
		(5 "F.SilkS" user "Ref Des/Silkscreen Top")
		(7 "B.SilkS" user "Ref Des/Silkscreen Bottom")
		(1 "F.Mask" user "Board Geometry/Soldermask Top")
		(3 "B.Mask" user "Board Geometry/Soldermask Bottom")
		(17 "Dwgs.User" user "User.Drawings")
		(19 "Cmts.User" user "User.Comments")
		(21 "Eco1.User" user "User.Eco1")
		(23 "Eco2.User" user "User.Eco2")
		(25 "Edge.Cuts" user "Board Geometry/Outline")
		(27 "Margin" user)
		(31 "F.CrtYd" user "Package Geometry/Place Bound Top")
		(29 "B.CrtYd" user "Package Geometry/Place Bound Bottom")
		(35 "F.Fab" user "Ref Des/Assembly Top")
		(33 "B.Fab" user "Ref Des/Assembly Bottom")
	)
	(footprint ""
		(layer "F.Cu")
		(at 194.2211 -403.284182 180)
		(property "Reference" "PC2184"
			(at 0 0 180)
			(layer "F.SilkS")
			(hide yes)
			(effects
				(font
					(size 1.27 1.27)
				)
			)
		)
		(property "Value" ""
			(at 0 0 180)
			(layer "F.Fab")
			(effects
				(font
					(size 1.27 1.27)
				)
			)
		)
		(duplicate_pad_numbers_are_jumpers no)
		(fp_line
			(start 0.7874 0.4064)
			(end -0.7874 0.4064)
			(stroke
				(width 0.1524)
				(type default)
			)
			(layer "F.SilkS")
		)
		(fp_line
			(start 0.7874 -0.4064)
			(end 0.7874 0.4064)
			(stroke
				(width 0.1524)
				(type default)
			)
			(layer "F.SilkS")
		)
		(fp_line
			(start -0.7874 0.4064)
			(end -0.7874 -0.4064)
			(stroke
				(width 0.1524)
				(type default)
			)
			(layer "F.SilkS")
		)
		(fp_line
			(start -0.7874 -0.4064)
			(end 0.7874 -0.4064)
			(stroke
				(width 0.1524)
				(type default)
			)
			(layer "F.SilkS")
		)
		(fp_line
			(start 0.67945 0.3048)
			(end 0.120396 0.3048)
			(stroke
				(width 0.1)
				(type default)
			)
			(layer "F.Fab")
		)
		(fp_line
			(start 0.67945 -0.3048)
			(end 0.67945 0.3048)
			(stroke
				(width 0.1)
				(type default)
			)
			(layer "F.Fab")
		)
		(fp_line
			(start 0.12065 -0.2794)
			(end 0.12065 -0.3048)
			(stroke
				(width 0.1)
				(type default)
			)
			(layer "F.Fab")
		)
		(fp_line
			(start 0.12065 -0.3048)
			(end 0.67945 -0.3048)
			(stroke
				(width 0.1)
				(type default)
			)
			(layer "F.Fab")
		)
		(fp_line
			(start 0.120396 0.3048)
			(end 0.120396 0.2794)
			(stroke
				(width 0.1)
				(type default)
			)
			(layer "F.Fab")
		)
		(fp_line
			(start 0.120396 0.2794)
			(end -0.12065 0.2794)
			(stroke
				(width 0.1)
				(type default)
			)
			(layer "F.Fab")
		)
		(fp_line
			(start -0.12065 0.3048)
			(end -0.67945 0.3048)
			(stroke
				(width 0.1)
				(type default)
			)
			(layer "F.Fab")
		)
		(fp_line
			(start -0.12065 0.2794)
			(end -0.12065 0.3048)
			(stroke
				(width 0.1)
				(type default)
			)
			(layer "F.Fab")
		)
		(fp_line
			(start -0.12065 -0.2794)
			(end 0.12065 -0.2794)
			(stroke
				(width 0.1)
				(type default)
			)
			(layer "F.Fab")
		)
		(fp_line
			(start -0.12065 -0.305054)
			(end -0.12065 -0.2794)
			(stroke
				(width 0.1)
				(type default)
			)
			(layer "F.Fab")
		)
		(fp_line
			(start -0.67945 0.3048)
			(end -0.67945 -0.305054)
			(stroke
				(width 0.1)
				(type default)
			)
			(layer "F.Fab")
		)
		(fp_line
			(start -0.67945 -0.305054)
			(end -0.12065 -0.305054)
			(stroke
				(width 0.1)
				(type default)
			)
			(layer "F.Fab")
		)
		(pad "1" smd circle
			(at -0.40005 0 180)
			(size 0 0)
			(layers "F.Cu" "F.Mask" "F.Paste")
			(net "HSC_SS")
		)
		(pad "2" smd circle
			(at 0.40005 0 180)
			(size 0 0)
			(layers "F.Cu" "F.Mask" "F.Paste")
			(net "AGND_HSC")
		)
	)
	(footprint ""
		(layer "F.Cu")
		(at 122.180096 -160.5407 90)
		(property "Reference" "PC334"
			(at 0 0 90)
			(layer "F.SilkS")
			(hide yes)
			(effects
				(font
					(size 1.27 1.27)
				)
			)
		)
		(property "Value" ""
			(at 0 0 90)
			(layer "F.Fab")
			(effects
				(font
					(size 1.27 1.27)
				)
			)
		)
		(duplicate_pad_numbers_are_jumpers no)
		(fp_line
			(start 0.7874 -0.4064)
			(end 0.7874 0.4064)
			(stroke
				(width 0.1524)
				(type default)
			)
			(layer "F.SilkS")
		)
		(fp_line
			(start -0.7874 -0.4064)
			(end 0.7874 -0.4064)
			(stroke
				(width 0.1524)
				(type default)
			)
			(layer "F.SilkS")
		)
		(fp_line
			(start 0.7874 0.4064)
			(end -0.7874 0.4064)
			(stroke
				(width 0.1524)
				(type default)
			)
			(layer "F.SilkS")
		)
		(fp_line
			(start -0.7874 0.4064)
			(end -0.7874 -0.4064)
			(stroke
				(width 0.1524)
				(type default)
			)
			(layer "F.SilkS")
		)
		(fp_line
			(start -0.12065 -0.305054)
			(end -0.12065 -0.2794)
			(stroke
				(width 0.1)
				(type default)
			)
			(layer "F.Fab")
		)
		(fp_line
			(start -0.67945 -0.305054)
			(end -0.12065 -0.305054)
			(stroke
				(width 0.1)
				(type default)
			)
			(layer "F.Fab")
		)
		(fp_line
			(start 0.67945 -0.3048)
			(end 0.67945 0.3048)
			(stroke
				(width 0.1)
				(type default)
			)
			(layer "F.Fab")
		)
		(fp_line
			(start 0.12065 -0.3048)
			(end 0.67945 -0.3048)
			(stroke
				(width 0.1)
				(type default)
			)
			(layer "F.Fab")
		)
		(fp_line
			(start 0.12065 -0.2794)
			(end 0.12065 -0.3048)
			(stroke
				(width 0.1)
				(type default)
			)
			(layer "F.Fab")
		)
		(fp_line
			(start -0.12065 -0.2794)
			(end 0.12065 -0.2794)
			(stroke
				(width 0.1)
				(type default)
			)
			(layer "F.Fab")
		)
		(fp_line
			(start 0.120396 0.2794)
			(end -0.12065 0.2794)
			(stroke
				(width 0.1)
				(type default)
			)
			(layer "F.Fab")
		)
		(fp_line
			(start -0.12065 0.2794)
			(end -0.12065 0.3048)
			(stroke
				(width 0.1)
				(type default)
			)
			(layer "F.Fab")
		)
		(fp_line
			(start 0.67945 0.3048)
			(end 0.120396 0.3048)
			(stroke
				(width 0.1)
				(type default)
			)
			(layer "F.Fab")
		)
		(fp_line
			(start 0.120396 0.3048)
			(end 0.120396 0.2794)
			(stroke
				(width 0.1)
				(type default)
			)
			(layer "F.Fab")
		)
		(fp_line
			(start -0.12065 0.3048)
			(end -0.67945 0.3048)
			(stroke
				(width 0.1)
				(type default)
			)
			(layer "F.Fab")
		)
		(fp_line
			(start -0.67945 0.3048)
			(end -0.67945 -0.305054)
			(stroke
				(width 0.1)
				(type default)
			)
			(layer "F.Fab")
		)
		(pad "1" smd circle
			(at -0.40005 0 90)
			(size 0 0)
			(layers "F.Cu" "F.Mask" "F.Paste")
			(net "SW_PVDDCR_SOC_P1_BOOT2_RC")
		)
		(pad "2" smd circle
			(at 0.40005 0 90)
			(size 0 0)
			(layers "F.Cu" "F.Mask" "F.Paste")
			(net "SW_PVDDCR_SOC_P1_PH2")
		)
	)
	(footprint ""
		(layer "F.Cu")
		(at 8.334248 -131.32435)
		(property "Reference" "R4081"
			(at 0 0 0)
			(layer "F.SilkS")
			(hide yes)
			(effects
				(font
					(size 1.27 1.27)
				)
			)
		)
		(property "Value" ""
			(at 0 0 0)
			(layer "F.Fab")
			(effects
				(font
					(size 1.27 1.27)
				)
			)
		)
		(duplicate_pad_numbers_are_jumpers no)
		(fp_line
			(start -0.7874 -0.4064)
			(end 0.7874 -0.4064)
			(stroke
				(width 0.1524)
				(type default)
			)
			(layer "F.SilkS")
		)
		(fp_line
			(start -0.7874 0.4064)
			(end -0.7874 -0.4064)
			(stroke
				(width 0.1524)
				(type default)
			)
			(layer "F.SilkS")
		)
		(fp_line
			(start 0.7874 -0.4064)
			(end 0.7874 0.4064)
			(stroke
				(width 0.1524)
				(type default)
			)
			(layer "F.SilkS")
		)
		(fp_line
			(start 0.7874 0.4064)
			(end -0.7874 0.4064)
			(stroke
				(width 0.1524)
				(type default)
			)
			(layer "F.SilkS")
		)
		(fp_line
			(start -0.67945 -0.305054)
			(end -0.12065 -0.305054)
			(stroke
				(width 0.1)
				(type default)
			)
			(layer "F.Fab")
		)
		(fp_line
			(start -0.67945 0.3048)
			(end -0.67945 -0.305054)
			(stroke
				(width 0.1)
				(type default)
			)
			(layer "F.Fab")
		)
		(fp_line
			(start -0.12065 -0.305054)
			(end -0.12065 -0.2794)
			(stroke
				(width 0.1)
				(type default)
			)
			(layer "F.Fab")
		)
		(fp_line
			(start -0.12065 -0.2794)
			(end 0.12065 -0.2794)
			(stroke
				(width 0.1)
				(type default)
			)
			(layer "F.Fab")
		)
		(fp_line
			(start -0.12065 0.2794)
			(end -0.12065 0.3048)
			(stroke
				(width 0.1)
				(type default)
			)
			(layer "F.Fab")
		)
		(fp_line
			(start -0.12065 0.3048)
			(end -0.67945 0.3048)
			(stroke
				(width 0.1)
				(type default)
			)
			(layer "F.Fab")
		)
		(fp_line
			(start 0.120396 0.2794)
			(end -0.12065 0.2794)
			(stroke
				(width 0.1)
				(type default)
			)
			(layer "F.Fab")
		)
		(fp_line
			(start 0.120396 0.3048)
			(end 0.120396 0.2794)
			(stroke
				(width 0.1)
				(type default)
			)
			(layer "F.Fab")
		)
		(fp_line
			(start 0.12065 -0.3048)
			(end 0.67945 -0.3048)
			(stroke
				(width 0.1)
				(type default)
			)
			(layer "F.Fab")
		)
		(fp_line
			(start 0.12065 -0.2794)
			(end 0.12065 -0.3048)
			(stroke
				(width 0.1)
				(type default)
			)
			(layer "F.Fab")
		)
		(fp_line
			(start 0.67945 -0.3048)
			(end 0.67945 0.3048)
			(stroke
				(width 0.1)
				(type default)
			)
			(layer "F.Fab")
		)
		(fp_line
			(start 0.67945 0.3048)
			(end 0.120396 0.3048)
			(stroke
				(width 0.1)
				(type default)
			)
			(layer "F.Fab")
		)
		(pad "1" smd circle
			(at -0.40005 0)
			(size 0 0)
			(layers "F.Cu" "F.Mask" "F.Paste")
			(net "P3V3_AUX")
		)
		(pad "2" smd circle
			(at 0.40005 0)
			(size 0 0)
			(layers "F.Cu" "F.Mask" "F.Paste")
			(net "CLK_GEN2_SMB_SADR")
		)
	)
	(footprint ""
		(layer "F.Cu")
		(at 226.0981 -405.036782 180)
		(property "Reference" "PC2227"
			(at 0 0 180)
			(layer "F.SilkS")
			(hide yes)
			(effects
				(font
					(size 1.27 1.27)
				)
			)
		)
		(property "Value" ""
			(at 0 0 180)
			(layer "F.Fab")
			(effects
				(font
					(size 1.27 1.27)
				)
			)
		)
		(duplicate_pad_numbers_are_jumpers no)
		(fp_line
			(start 0.7874 0.4064)
			(end -0.7874 0.4064)
			(stroke
				(width 0.1524)
				(type default)
			)
			(layer "F.SilkS")
		)
		(fp_line
			(start 0.7874 -0.4064)
			(end 0.7874 0.4064)
			(stroke
				(width 0.1524)
				(type default)
			)
			(layer "F.SilkS")
		)
		(fp_line
			(start -0.7874 0.4064)
			(end -0.7874 -0.4064)
			(stroke
				(width 0.1524)
				(type default)
			)
			(layer "F.SilkS")
		)
		(fp_line
			(start -0.7874 -0.4064)
			(end 0.7874 -0.4064)
			(stroke
				(width 0.1524)
				(type default)
			)
			(layer "F.SilkS")
		)
		(fp_line
			(start 0.67945 0.3048)
			(end 0.120396 0.3048)
			(stroke
				(width 0.1)
				(type default)
			)
			(layer "F.Fab")
		)
		(fp_line
			(start 0.67945 -0.3048)
			(end 0.67945 0.3048)
			(stroke
				(width 0.1)
				(type default)
			)
			(layer "F.Fab")
		)
		(fp_line
			(start 0.12065 -0.2794)
			(end 0.12065 -0.3048)
			(stroke
				(width 0.1)
				(type default)
			)
			(layer "F.Fab")
		)
		(fp_line
			(start 0.12065 -0.3048)
			(end 0.67945 -0.3048)
			(stroke
				(width 0.1)
				(type default)
			)
			(layer "F.Fab")
		)
		(fp_line
			(start 0.120396 0.3048)
			(end 0.120396 0.2794)
			(stroke
				(width 0.1)
				(type default)
			)
			(layer "F.Fab")
		)
		(fp_line
			(start 0.120396 0.2794)
			(end -0.12065 0.2794)
			(stroke
				(width 0.1)
				(type default)
			)
			(layer "F.Fab")
		)
		(fp_line
			(start -0.12065 0.3048)
			(end -0.67945 0.3048)
			(stroke
				(width 0.1)
				(type default)
			)
			(layer "F.Fab")
		)
		(fp_line
			(start -0.12065 0.2794)
			(end -0.12065 0.3048)
			(stroke
				(width 0.1)
				(type default)
			)
			(layer "F.Fab")
		)
		(fp_line
			(start -0.12065 -0.2794)
			(end 0.12065 -0.2794)
			(stroke
				(width 0.1)
				(type default)
			)
			(layer "F.Fab")
		)
		(fp_line
			(start -0.12065 -0.305054)
			(end -0.12065 -0.2794)
			(stroke
				(width 0.1)
				(type default)
			)
			(layer "F.Fab")
		)
		(fp_line
			(start -0.67945 0.3048)
			(end -0.67945 -0.305054)
			(stroke
				(width 0.1)
				(type default)
			)
			(layer "F.Fab")
		)
		(fp_line
			(start -0.67945 -0.305054)
			(end -0.12065 -0.305054)
			(stroke
				(width 0.1)
				(type default)
			)
			(layer "F.Fab")
		)
		(pad "1" smd circle
			(at -0.40005 0 180)
			(size 0 0)
			(layers "F.Cu" "F.Mask" "F.Paste")
			(net "HSC_SS")
		)
		(pad "2" smd circle
			(at 0.40005 0 180)
			(size 0 0)
			(layers "F.Cu" "F.Mask" "F.Paste")
			(net "AGND_HSC")
		)
	)
	(footprint ""
		(layer "F.Cu")
		(at 233.748072 -69.560186 -90)
		(property "Reference" "R1038"
			(at 0 0 270)
			(layer "F.SilkS")
			(hide yes)
			(effects
				(font
					(size 1.27 1.27)
				)
			)
		)
		(property "Value" ""
			(at 0 0 270)
			(layer "F.Fab")
			(effects
				(font
					(size 1.27 1.27)
				)
			)
		)
		(duplicate_pad_numbers_are_jumpers no)
		(fp_line
			(start -0.7874 0.4064)
			(end -0.7874 -0.4064)
			(stroke
				(width 0.1524)
				(type default)
			)
			(layer "F.SilkS")
		)
		(fp_line
			(start 0.7874 0.4064)
			(end -0.7874 0.4064)
			(stroke
				(width 0.1524)
				(type default)
			)
			(layer "F.SilkS")
		)
		(fp_line
			(start -0.7874 -0.4064)
			(end 0.7874 -0.4064)
			(stroke
				(width 0.1524)
				(type default)
			)
			(layer "F.SilkS")
		)
		(fp_line
			(start 0.7874 -0.4064)
			(end 0.7874 0.4064)
			(stroke
				(width 0.1524)
				(type default)
			)
			(layer "F.SilkS")
		)
		(fp_line
			(start -0.67945 0.3048)
			(end -0.67945 -0.305054)
			(stroke
				(width 0.1)
				(type default)
			)
			(layer "F.Fab")
		)
		(fp_line
			(start -0.12065 0.3048)
			(end -0.67945 0.3048)
			(stroke
				(width 0.1)
				(type default)
			)
			(layer "F.Fab")
		)
		(fp_line
			(start 0.120396 0.3048)
			(end 0.120396 0.2794)
			(stroke
				(width 0.1)
				(type default)
			)
			(layer "F.Fab")
		)
		(fp_line
			(start 0.67945 0.3048)
			(end 0.120396 0.3048)
			(stroke
				(width 0.1)
				(type default)
			)
			(layer "F.Fab")
		)
		(fp_line
			(start -0.12065 0.2794)
			(end -0.12065 0.3048)
			(stroke
				(width 0.1)
				(type default)
			)
			(layer "F.Fab")
		)
		(fp_line
			(start 0.120396 0.2794)
			(end -0.12065 0.2794)
			(stroke
				(width 0.1)
				(type default)
			)
			(layer "F.Fab")
		)
		(fp_line
			(start -0.12065 -0.2794)
			(end 0.12065 -0.2794)
			(stroke
				(width 0.1)
				(type default)
			)
			(layer "F.Fab")
		)
		(fp_line
			(start 0.12065 -0.2794)
			(end 0.12065 -0.3048)
			(stroke
				(width 0.1)
				(type default)
			)
			(layer "F.Fab")
		)
		(fp_line
			(start 0.12065 -0.3048)
			(end 0.67945 -0.3048)
			(stroke
				(width 0.1)
				(type default)
			)
			(layer "F.Fab")
		)
		(fp_line
			(start 0.67945 -0.3048)
			(end 0.67945 0.3048)
			(stroke
				(width 0.1)
				(type default)
			)
			(layer "F.Fab")
		)
		(fp_line
			(start -0.67945 -0.305054)
			(end -0.12065 -0.305054)
			(stroke
				(width 0.1)
				(type default)
			)
			(layer "F.Fab")
		)
		(fp_line
			(start -0.12065 -0.305054)
			(end -0.12065 -0.2794)
			(stroke
				(width 0.1)
				(type default)
			)
			(layer "F.Fab")
		)
		(pad "1" smd circle
			(at -0.40005 0 270)
			(size 0 0)
			(layers "F.Cu" "F.Mask" "F.Paste")
			(net "FM_LED_ACTIVE_E1S_0_R_BUF")
		)
		(pad "2" smd circle
			(at 0.40005 0 270)
			(size 0 0)
			(layers "F.Cu" "F.Mask" "F.Paste")
			(net "FM_LED_ACTIVE_E1S_0_BUF")
		)
	)
	(footprint ""
		(layer "F.Cu")
		(at 69.211444 -408.517344 -90)
		(property "Reference" "C6644"
			(at 0 0 270)
			(layer "F.SilkS")
			(hide yes)
			(effects
				(font
					(size 1.27 1.27)
				)
			)
		)
		(property "Value" ""
			(at 0 0 270)
			(layer "F.Fab")
			(effects
				(font
					(size 1.27 1.27)
				)
			)
		)
		(duplicate_pad_numbers_are_jumpers no)
		(fp_line
			(start -0.299974 0.150114)
			(end -0.299974 -0.150114)
			(stroke
				(width 0.1)
				(type default)
			)
			(layer "F.Fab")
		)
		(fp_line
			(start 0.299974 0.150114)
			(end -0.299974 0.150114)
			(stroke
				(width 0.1)
				(type default)
			)
			(layer "F.Fab")
		)
		(fp_line
			(start -0.299974 -0.150114)
			(end 0.299974 -0.150114)
			(stroke
				(width 0.1)
				(type default)
			)
			(layer "F.Fab")
		)
		(fp_line
			(start 0.299974 -0.150114)
			(end 0.299974 0.150114)
			(stroke
				(width 0.1)
				(type default)
			)
			(layer "F.Fab")
		)
		(pad "1" smd rect
			(at -0.2667 0 270)
			(size 0.3048 0.381)
			(layers "F.Cu" "F.Mask" "F.Paste")
			(net "P5E_CPU1_P0_TX_BUF_C_DN<7>")
		)
		(pad "2" smd rect
			(at 0.2667 0 270)
			(size 0.3048 0.381)
			(layers "F.Cu" "F.Mask" "F.Paste")
			(net "P5E_CPU1_P0_TX_BUF_DN<7>")
		)
	)
	(footprint ""
		(layer "F.Cu")
		(at 164.544756 -41.112948)
		(property "Reference" "R3301"
			(at 0 0 0)
			(layer "F.SilkS")
			(hide yes)
			(effects
				(font
					(size 1.27 1.27)
				)
			)
		)
		(property "Value" ""
			(at 0 0 0)
			(layer "F.Fab")
			(effects
				(font
					(size 1.27 1.27)
				)
			)
		)
		(duplicate_pad_numbers_are_jumpers no)
		(fp_line
			(start -0.7874 -0.4064)
			(end 0.7874 -0.4064)
			(stroke
				(width 0.1524)
				(type default)
			)
			(layer "F.SilkS")
		)
		(fp_line
			(start -0.7874 0.4064)
			(end -0.7874 -0.4064)
			(stroke
				(width 0.1524)
				(type default)
			)
			(layer "F.SilkS")
		)
		(fp_line
			(start 0.7874 -0.4064)
			(end 0.7874 0.4064)
			(stroke
				(width 0.1524)
				(type default)
			)
			(layer "F.SilkS")
		)
		(fp_line
			(start 0.7874 0.4064)
			(end -0.7874 0.4064)
			(stroke
				(width 0.1524)
				(type default)
			)
			(layer "F.SilkS")
		)
		(fp_line
			(start -0.67945 -0.305054)
			(end -0.12065 -0.305054)
			(stroke
				(width 0.1)
				(type default)
			)
			(layer "F.Fab")
		)
		(fp_line
			(start -0.67945 0.3048)
			(end -0.67945 -0.305054)
			(stroke
				(width 0.1)
				(type default)
			)
			(layer "F.Fab")
		)
		(fp_line
			(start -0.12065 -0.305054)
			(end -0.12065 -0.2794)
			(stroke
				(width 0.1)
				(type default)
			)
			(layer "F.Fab")
		)
		(fp_line
			(start -0.12065 -0.2794)
			(end 0.12065 -0.2794)
			(stroke
				(width 0.1)
				(type default)
			)
			(layer "F.Fab")
		)
		(fp_line
			(start -0.12065 0.2794)
			(end -0.12065 0.3048)
			(stroke
				(width 0.1)
				(type default)
			)
			(layer "F.Fab")
		)
		(fp_line
			(start -0.12065 0.3048)
			(end -0.67945 0.3048)
			(stroke
				(width 0.1)
				(type default)
			)
			(layer "F.Fab")
		)
		(fp_line
			(start 0.120396 0.2794)
			(end -0.12065 0.2794)
			(stroke
				(width 0.1)
				(type default)
			)
			(layer "F.Fab")
		)
		(fp_line
			(start 0.120396 0.3048)
			(end 0.120396 0.2794)
			(stroke
				(width 0.1)
				(type default)
			)
			(layer "F.Fab")
		)
		(fp_line
			(start 0.12065 -0.3048)
			(end 0.67945 -0.3048)
			(stroke
				(width 0.1)
				(type default)
			)
			(layer "F.Fab")
		)
		(fp_line
			(start 0.12065 -0.2794)
			(end 0.12065 -0.3048)
			(stroke
				(width 0.1)
				(type default)
			)
			(layer "F.Fab")
		)
		(fp_line
			(start 0.67945 -0.3048)
			(end 0.67945 0.3048)
			(stroke
				(width 0.1)
				(type default)
			)
			(layer "F.Fab")
		)
		(fp_line
			(start 0.67945 0.3048)
			(end 0.120396 0.3048)
			(stroke
				(width 0.1)
				(type default)
			)
			(layer "F.Fab")
		)
		(pad "1" smd circle
			(at -0.40005 0)
			(size 0 0)
			(layers "F.Cu" "F.Mask" "F.Paste")
			(net "M2_0_PEWAKE_R_N")
		)
		(pad "2" smd circle
			(at 0.40005 0)
			(size 0 0)
			(layers "F.Cu" "F.Mask" "F.Paste")
			(net "M2_0_PEWAKE_N")
		)
	)
)
